# T6G (Grand Teton) — schematic netlist excerpt (pin names and nets, part order shuffled) for the footprints in the layout excerpt that follows; sources: Cadence DE-HDL packaged netlist, KiCad conversion of 04192023_DAF0TMB3IC0_F0TG_MB_C_brd_V02_OCP.brd

C816  Q_CAP_DIFFBUS  DIFF BUS_0.22UF 6.3V 20% X6S  pkg C0201  page 65 : \1\ = P5E_CPU1_P0_TX_C_DN<10> ; \2\ = P5E_CPU1_P0_TX_DN<10>
PC6525  Q_CAP  1UF 25V 10% X6S  pkg C0402  page 361 : A = P1V8_RETIMER_CPU1_VCC ; B = GND

(kicad_pcb
	(version 20260206)
	(generator "pcbnew")
	(generator_version "10.0")
	(general
		(thickness 1.6)
		(legacy_teardrops no)
	)
	(paper "A4")
	(title_block
		(title "04192023_DAF0TMB3IC0_F0TG_MB_C_brd_V02_OCP.brd")
		(comment 1 "Grand Teton / footprints 766-767 of 8354")
	)
	(layers
		(0 "F.Cu" signal "TOP")
		(4 "In1.Cu" signal "GND")
		(6 "In2.Cu" signal "IN1")
		(8 "In3.Cu" signal "GND1")
		(10 "In4.Cu" signal "IN2")
		(12 "In5.Cu" signal "GND2")
		(14 "In6.Cu" signal "IN3")
		(16 "In7.Cu" signal "GND3")
		(18 "In8.Cu" signal "VCC")
		(20 "In9.Cu" signal "VCC1")
		(22 "In10.Cu" signal "GND4")
		(24 "In11.Cu" signal "IN4")
		(26 "In12.Cu" signal "GND5")
		(28 "In13.Cu" signal "IN5")
		(30 "In14.Cu" signal "GND6")
		(32 "In15.Cu" signal "IN6")
		(34 "In16.Cu" signal "GND7")
		(2 "B.Cu" signal "BOTTOM")
		(9 "F.Adhes" user "F.Adhesive")
		(11 "B.Adhes" user "B.Adhesive")
		(13 "F.Paste" user "Package Geometry/Pastemask Top")
		(15 "B.Paste" user "Package Geometry/Pastemask Bottom")
		(5 "F.SilkS" user "Ref Des/Silkscreen Top")
		(7 "B.SilkS" user "Ref Des/Silkscreen Bottom")
		(1 "F.Mask" user "Board Geometry/Soldermask Top")
		(3 "B.Mask" user "Board Geometry/Soldermask Bottom")
		(17 "Dwgs.User" user "User.Drawings")
		(19 "Cmts.User" user "User.Comments")
		(21 "Eco1.User" user "User.Eco1")
		(23 "Eco2.User" user "User.Eco2")
		(25 "Edge.Cuts" user "Board Geometry/Outline")
		(27 "Margin" user)
		(31 "F.CrtYd" user "Package Geometry/Place Bound Top")
		(29 "B.CrtYd" user "Package Geometry/Place Bound Bottom")
		(35 "F.Fab" user "Ref Des/Assembly Top")
		(33 "B.Fab" user "Ref Des/Assembly Bottom")
	)
	(footprint ""
		(layer "F.Cu")
		(at 62.623954 -375.49963 -90)
		(property "Reference" "C816"
			(at 0 0 270)
			(layer "F.SilkS")
			(hide yes)
			(effects
				(font
					(size 1.27 1.27)
				)
			)
		)
		(property "Value" ""
			(at 0 0 270)
			(layer "F.Fab")
			(effects
				(font
					(size 1.27 1.27)
				)
			)
		)
		(duplicate_pad_numbers_are_jumpers no)
		(fp_line
			(start -0.299974 0.150114)
			(end -0.299974 -0.150114)
			(stroke
				(width 0.1)
				(type default)
			)
			(layer "F.Fab")
		)
		(fp_line
			(start 0.299974 0.150114)
			(end -0.299974 0.150114)
			(stroke
				(width 0.1)
				(type default)
			)
			(layer "F.Fab")
		)
		(fp_line
			(start -0.299974 -0.150114)
			(end 0.299974 -0.150114)
			(stroke
				(width 0.1)
				(type default)
			)
			(layer "F.Fab")
		)
		(fp_line
			(start 0.299974 -0.150114)
			(end 0.299974 0.150114)
			(stroke
				(width 0.1)
				(type default)
			)
			(layer "F.Fab")
		)
		(pad "1" smd rect
			(at -0.2667 0 270)
			(size 0.3048 0.381)
			(layers "F.Cu" "F.Mask" "F.Paste")
			(net "P5E_CPU1_P0_TX_C_DN<10>")
		)
		(pad "2" smd rect
			(at 0.2667 0 270)
			(size 0.3048 0.381)
			(layers "F.Cu" "F.Mask" "F.Paste")
			(net "P5E_CPU1_P0_TX_DN<10>")
		)
	)
	(footprint ""
		(layer "F.Cu")
		(at 234.301538 -293.13505 -90)
		(property "Reference" "PC6525"
			(at 0 0 270)
			(layer "F.SilkS")
			(hide yes)
			(effects
				(font
					(size 1.27 1.27)
				)
			)
		)
		(property "Value" ""
			(at 0 0 270)
			(layer "F.Fab")
			(effects
				(font
					(size 1.27 1.27)
				)
			)
		)
		(duplicate_pad_numbers_are_jumpers no)
		(fp_line
			(start -0.7874 0.4064)
			(end -0.7874 -0.4064)
			(stroke
				(width 0.1524)
				(type default)
			)
			(layer "F.SilkS")
		)
		(fp_line
			(start 0.7874 0.4064)
			(end -0.7874 0.4064)
			(stroke
				(width 0.1524)
				(type default)
			)
			(layer "F.SilkS")
		)
		(fp_line
			(start -0.7874 -0.4064)
			(end 0.7874 -0.4064)
			(stroke
				(width 0.1524)
				(type default)
			)
			(layer "F.SilkS")
		)
		(fp_line
			(start 0.7874 -0.4064)
			(end 0.7874 0.4064)
			(stroke
				(width 0.1524)
				(type default)
			)
			(layer "F.SilkS")
		)
		(fp_line
			(start -0.67945 0.3048)
			(end -0.67945 -0.305054)
			(stroke
				(width 0.1)
				(type default)
			)
			(layer "F.Fab")
		)
		(fp_line
			(start -0.12065 0.3048)
			(end -0.67945 0.3048)
			(stroke
				(width 0.1)
				(type default)
			)
			(layer "F.Fab")
		)
		(fp_line
			(start 0.120396 0.3048)
			(end 0.120396 0.2794)
			(stroke
				(width 0.1)
				(type default)
			)
			(layer "F.Fab")
		)
		(fp_line
			(start 0.67945 0.3048)
			(end 0.120396 0.3048)
			(stroke
				(width 0.1)
				(type default)
			)
			(layer "F.Fab")
		)
		(fp_line
			(start -0.12065 0.2794)
			(end -0.12065 0.3048)
			(stroke
				(width 0.1)
				(type default)
			)
			(layer "F.Fab")
		)
		(fp_line
			(start 0.120396 0.2794)
			(end -0.12065 0.2794)
			(stroke
				(width 0.1)
				(type default)
			)
			(layer "F.Fab")
		)
		(fp_line
			(start -0.12065 -0.2794)
			(end 0.12065 -0.2794)
			(stroke
				(width 0.1)
				(type default)
			)
			(layer "F.Fab")
		)
		(fp_line
			(start 0.12065 -0.2794)
			(end 0.12065 -0.3048)
			(stroke
				(width 0.1)
				(type default)
			)
			(layer "F.Fab")
		)
		(fp_line
			(start 0.12065 -0.3048)
			(end 0.67945 -0.3048)
			(stroke
				(width 0.1)
				(type default)
			)
			(layer "F.Fab")
		)
		(fp_line
			(start 0.67945 -0.3048)
			(end 0.67945 0.3048)
			(stroke
				(width 0.1)
				(type default)
			)
			(layer "F.Fab")
		)
		(fp_line
			(start -0.67945 -0.305054)
			(end -0.12065 -0.305054)
			(stroke
				(width 0.1)
				(type default)
			)
			(layer "F.Fab")
		)
		(fp_line
			(start -0.12065 -0.305054)
			(end -0.12065 -0.2794)
			(stroke
				(width 0.1)
				(type default)
			)
			(layer "F.Fab")
		)
		(pad "1" smd circle
			(at -0.40005 0 270)
			(size 0 0)
			(layers "F.Cu" "F.Mask" "F.Paste")
			(net "P1V8_RETIMER_CPU1_VCC")
		)
		(pad "2" smd circle
			(at 0.40005 0 270)
			(size 0 0)
			(layers "F.Cu" "F.Mask" "F.Paste")
			(net "GND")
		)
	)
)
